# SCM (Grand Teton) — schematic netlist excerpt (pin names and nets, part order shuffled) for the footprints in the layout excerpt that follows; sources: Cadence DE-HDL packaged netlist, KiCad conversion of 12092022_DA0F0TMDCD0_F0T_Management_Board_D_brd_V3_OCP.brd

R700  Q_RES  0 5% CHIP  pkg 0402LF  page 47 : A = LED_POSTCODE_0 ; B = LED_POSTCODE_0_R1
C269  Q_CAP  0.1UF 25V 10% X7R  pkg 0402  page 41 : A = PVCCA_AUX_PLD ; B = GND

(kicad_pcb
	(version 20260206)
	(generator "pcbnew")
	(generator_version "10.0")
	(general
		(thickness 1.6)
		(legacy_teardrops no)
	)
	(paper "A4")
	(title_block
		(title "12092022_DA0F0TMDCD0_F0T_Management_Board_D_brd_V3_OCP.brd")
		(comment 1 "Grand Teton / footprints 1041-1042 of 1440")
	)
	(layers
		(0 "F.Cu" signal "TOP")
		(4 "In1.Cu" signal "GND")
		(6 "In2.Cu" signal "IN1")
		(8 "In3.Cu" signal "GND1")
		(10 "In4.Cu" signal "IN2")
		(12 "In5.Cu" signal "VCC")
		(14 "In6.Cu" signal "VCC1")
		(16 "In7.Cu" signal "IN3")
		(18 "In8.Cu" signal "GND2")
		(20 "In9.Cu" signal "IN4")
		(22 "In10.Cu" signal "GND3")
		(2 "B.Cu" signal "BOTTOM")
		(9 "F.Adhes" user "F.Adhesive")
		(11 "B.Adhes" user "B.Adhesive")
		(13 "F.Paste" user "Package Geometry/Pastemask Top")
		(15 "B.Paste" user "Package Geometry/Pastemask Bottom")
		(5 "F.SilkS" user "Ref Des/Silkscreen Top")
		(7 "B.SilkS" user "Ref Des/Silkscreen Bottom")
		(1 "F.Mask" user "Board Geometry/Soldermask Top")
		(3 "B.Mask" user "Board Geometry/Soldermask Bottom")
		(17 "Dwgs.User" user "User.Drawings")
		(19 "Cmts.User" user "User.Comments")
		(21 "Eco1.User" user "User.Eco1")
		(23 "Eco2.User" user "User.Eco2")
		(25 "Edge.Cuts" user "Board Geometry/Outline")
		(27 "Margin" user)
		(31 "F.CrtYd" user "Package Geometry/Place Bound Top")
		(29 "B.CrtYd" user "Package Geometry/Place Bound Bottom")
		(35 "F.Fab" user "Ref Des/Assembly Top")
		(33 "B.Fab" user "Ref Des/Assembly Bottom")
	)
	(footprint ""
		(layer "B.Cu")
		(at 26.659332 -88.787224 -90)
		(property "Reference" "C269"
			(at 0 0 90)
			(layer "B.SilkS")
			(hide yes)
			(effects
				(font
					(size 1.27 1.27)
				)
				(justify mirror)
			)
		)
		(property "Value" ""
			(at 0 0 90)
			(layer "B.Fab")
			(effects
				(font
					(size 1.27 1.27)
				)
				(justify mirror)
			)
		)
		(duplicate_pad_numbers_are_jumpers no)
		(fp_line
			(start -0.69215 0.2921)
			(end 0.69215 0.2921)
			(stroke
				(width 0.1524)
				(type default)
			)
			(layer "B.SilkS")
		)
		(fp_line
			(start 0.69215 0.2921)
			(end 0.69215 -0.2921)
			(stroke
				(width 0.1524)
				(type default)
			)
			(layer "B.SilkS")
		)
		(fp_line
			(start -0.69215 -0.2921)
			(end -0.69215 0.2921)
			(stroke
				(width 0.1524)
				(type default)
			)
			(layer "B.SilkS")
		)
		(fp_line
			(start 0.69215 -0.2921)
			(end -0.69215 -0.2921)
			(stroke
				(width 0.1524)
				(type default)
			)
			(layer "B.SilkS")
		)
		(fp_line
			(start -0.51435 0.2794)
			(end 0.51435 0.2794)
			(stroke
				(width 0.1)
				(type default)
			)
			(layer "B.Fab")
		)
		(fp_line
			(start 0.51435 0.2794)
			(end 0.51435 -0.2794)
			(stroke
				(width 0.1)
				(type default)
			)
			(layer "B.Fab")
		)
		(fp_line
			(start -0.51435 -0.2794)
			(end -0.51435 0.2794)
			(stroke
				(width 0.1)
				(type default)
			)
			(layer "B.Fab")
		)
		(fp_line
			(start 0.51435 -0.2794)
			(end -0.51435 -0.2794)
			(stroke
				(width 0.1)
				(type default)
			)
			(layer "B.Fab")
		)
		(pad "1" smd circle
			(at 0.40005 0 90)
			(size 0 0)
			(layers "B.Cu" "B.Mask" "B.Paste")
			(net "PVCCA_AUX_PLD")
		)
		(pad "2" smd circle
			(at -0.40005 0 90)
			(size 0 0)
			(layers "B.Cu" "B.Mask" "B.Paste")
			(net "GND")
		)
		(zone
			(layer "B.Cu")
			(hatch none 0.5)
			(connect_pads
				(clearance 0)
			)
			(min_thickness 0.25)
			(keepout
				(tracks not_allowed)
				(vias allowed)
				(pads allowed)
				(copperpour not_allowed)
				(footprints allowed)
			)
			(placement
				(enabled no)
				(sheetname "")
			)
			(fill
				(thermal_gap 0.5)
				(thermal_bridge_width 0.5)
				(island_removal_mode 0)
			)
			(polygon
				(pts
					(xy 26.571702 -88.596724) (xy 26.513536 -88.688164) (xy 26.513536 -88.887554) (xy 26.571702 -88.977724)
					(xy 26.746962 -88.977724) (xy 26.805382 -88.887554) (xy 26.805382 -88.688164) (xy 26.747216 -88.596724)
				)
			)
		)
	)
	(footprint ""
		(layer "B.Cu")
		(at 79.8576 -30.988)
		(property "Reference" "R700"
			(at 0 0 0)
			(layer "B.SilkS")
			(hide yes)
			(effects
				(font
					(size 1.27 1.27)
				)
				(justify mirror)
			)
		)
		(property "Value" ""
			(at 0 0 0)
			(layer "B.Fab")
			(effects
				(font
					(size 1.27 1.27)
				)
				(justify mirror)
			)
		)
		(duplicate_pad_numbers_are_jumpers no)
		(fp_line
			(start -0.7874 -0.4064)
			(end -0.7874 0.4064)
			(stroke
				(width 0.1524)
				(type default)
			)
			(layer "B.SilkS")
		)
		(fp_line
			(start -0.7874 0.4064)
			(end 0.7874 0.4064)
			(stroke
				(width 0.1524)
				(type default)
			)
			(layer "B.SilkS")
		)
		(fp_line
			(start 0.7874 -0.4064)
			(end -0.7874 -0.4064)
			(stroke
				(width 0.1524)
				(type default)
			)
			(layer "B.SilkS")
		)
		(fp_line
			(start 0.7874 0.4064)
			(end 0.7874 -0.4064)
			(stroke
				(width 0.1524)
				(type default)
			)
			(layer "B.SilkS")
		)
		(fp_line
			(start -0.67945 -0.3048)
			(end -0.67945 0.3048)
			(stroke
				(width 0.1)
				(type default)
			)
			(layer "B.Fab")
		)
		(fp_line
			(start -0.67945 0.3048)
			(end -0.120396 0.3048)
			(stroke
				(width 0.1)
				(type default)
			)
			(layer "B.Fab")
		)
		(fp_line
			(start -0.12065 -0.3048)
			(end -0.67945 -0.3048)
			(stroke
				(width 0.1)
				(type default)
			)
			(layer "B.Fab")
		)
		(fp_line
			(start -0.12065 -0.2794)
			(end -0.12065 -0.3048)
			(stroke
				(width 0.1)
				(type default)
			)
			(layer "B.Fab")
		)
		(fp_line
			(start -0.120396 0.2794)
			(end 0.12065 0.2794)
			(stroke
				(width 0.1)
				(type default)
			)
			(layer "B.Fab")
		)
		(fp_line
			(start -0.120396 0.3048)
			(end -0.120396 0.2794)
			(stroke
				(width 0.1)
				(type default)
			)
			(layer "B.Fab")
		)
		(fp_line
			(start 0.12065 -0.305054)
			(end 0.12065 -0.2794)
			(stroke
				(width 0.1)
				(type default)
			)
			(layer "B.Fab")
		)
		(fp_line
			(start 0.12065 -0.2794)
			(end -0.12065 -0.2794)
			(stroke
				(width 0.1)
				(type default)
			)
			(layer "B.Fab")
		)
		(fp_line
			(start 0.12065 0.2794)
			(end 0.12065 0.3048)
			(stroke
				(width 0.1)
				(type default)
			)
			(layer "B.Fab")
		)
		(fp_line
			(start 0.12065 0.3048)
			(end 0.67945 0.3048)
			(stroke
				(width 0.1)
				(type default)
			)
			(layer "B.Fab")
		)
		(fp_line
			(start 0.67945 -0.305054)
			(end 0.12065 -0.305054)
			(stroke
				(width 0.1)
				(type default)
			)
			(layer "B.Fab")
		)
		(fp_line
			(start 0.67945 0.3048)
			(end 0.67945 -0.305054)
			(stroke
				(width 0.1)
				(type default)
			)
			(layer "B.Fab")
		)
		(pad "1" smd circle
			(at 0.40005 0 180)
			(size 0 0)
			(layers "B.Cu" "B.Mask" "B.Paste")
			(net "LED_POSTCODE_0")
		)
		(pad "2" smd circle
			(at -0.40005 0 180)
			(size 0 0)
			(layers "B.Cu" "B.Mask" "B.Paste")
			(net "LED_POSTCODE_0_R1")
		)
	)
)
